# S9S_MB_2U (Grand Teton) — schematic netlist excerpt (pin names and nets, part order shuffled) for the footprints in the layout excerpt that follows; sources: Cadence DE-HDL packaged netlist, KiCad conversion of 03242023_DA0F0TMBIJ0_F0T_Motherboard_J_brd_V01_OCP.brd

R3095  Q_RES  130 1% CHIP  pkg 0402LF  page 254 : A = LED_PWRGD_PVCCFA_EHV_FIVRA_CPU1 ; B = P3V3_AUX
PR521  Q_RES  100 1% CHIP  pkg 0402LF  page 274 : A = VSENSE_PVCCINFAON_CPU0_DP ; B = PVCCINFAON_CPU0

(kicad_pcb
	(version 20260206)
	(generator "pcbnew")
	(generator_version "10.0")
	(general
		(thickness 1.6)
		(legacy_teardrops no)
	)
	(paper "A4")
	(title_block
		(title "03242023_DA0F0TMBIJ0_F0T_Motherboard_J_brd_V01_OCP.brd")
		(comment 1 "Grand Teton / footprints 1-2 of 6105")
	)
	(layers
		(0 "F.Cu" signal "TOP")
		(4 "In1.Cu" signal "GND")
		(6 "In2.Cu" signal "IN1")
		(8 "In3.Cu" signal "GND1")
		(10 "In4.Cu" signal "IN2")
		(12 "In5.Cu" signal "GND2")
		(14 "In6.Cu" signal "IN3")
		(16 "In7.Cu" signal "GND3")
		(18 "In8.Cu" signal "VCC")
		(20 "In9.Cu" signal "VCC1")
		(22 "In10.Cu" signal "GND4")
		(24 "In11.Cu" signal "IN4")
		(26 "In12.Cu" signal "GND5")
		(28 "In13.Cu" signal "IN5")
		(30 "In14.Cu" signal "GND6")
		(32 "In15.Cu" signal "IN6")
		(34 "In16.Cu" signal "GND7")
		(2 "B.Cu" signal "BOTTOM")
		(9 "F.Adhes" user "F.Adhesive")
		(11 "B.Adhes" user "B.Adhesive")
		(13 "F.Paste" user "Package Geometry/Pastemask Top")
		(15 "B.Paste" user "Package Geometry/Pastemask Bottom")
		(5 "F.SilkS" user "Ref Des/Silkscreen Top")
		(7 "B.SilkS" user "Ref Des/Silkscreen Bottom")
		(1 "F.Mask" user "Board Geometry/Soldermask Top")
		(3 "B.Mask" user "Board Geometry/Soldermask Bottom")
		(17 "Dwgs.User" user "User.Drawings")
		(19 "Cmts.User" user "User.Comments")
		(21 "Eco1.User" user "User.Eco1")
		(23 "Eco2.User" user "User.Eco2")
		(25 "Edge.Cuts" user "Board Geometry/Outline")
		(27 "Margin" user)
		(31 "F.CrtYd" user "Package Geometry/Place Bound Top")
		(29 "B.CrtYd" user "Package Geometry/Place Bound Bottom")
		(35 "F.Fab" user "Ref Des/Assembly Top")
		(33 "B.Fab" user "Ref Des/Assembly Bottom")
	)
	(footprint ""
		(layer "F.Cu")
		(at 72.26681 -74.901552 -90)
		(property "Reference" "R3095"
			(at 0 0 270)
			(layer "F.SilkS")
			(hide yes)
			(effects
				(font
					(size 1.27 1.27)
				)
			)
		)
		(property "Value" ""
			(at 0 0 270)
			(layer "F.Fab")
			(effects
				(font
					(size 1.27 1.27)
				)
			)
		)
		(duplicate_pad_numbers_are_jumpers no)
		(fp_line
			(start -0.7874 0.4064)
			(end -0.7874 -0.4064)
			(stroke
				(width 0.1524)
				(type default)
			)
			(layer "F.SilkS")
		)
		(fp_line
			(start 0.7874 0.4064)
			(end -0.7874 0.4064)
			(stroke
				(width 0.1524)
				(type default)
			)
			(layer "F.SilkS")
		)
		(fp_line
			(start -0.7874 -0.4064)
			(end 0.7874 -0.4064)
			(stroke
				(width 0.1524)
				(type default)
			)
			(layer "F.SilkS")
		)
		(fp_line
			(start 0.7874 -0.4064)
			(end 0.7874 0.4064)
			(stroke
				(width 0.1524)
				(type default)
			)
			(layer "F.SilkS")
		)
		(fp_line
			(start -0.67945 0.3048)
			(end -0.67945 -0.305054)
			(stroke
				(width 0.1)
				(type default)
			)
			(layer "F.Fab")
		)
		(fp_line
			(start -0.12065 0.3048)
			(end -0.67945 0.3048)
			(stroke
				(width 0.1)
				(type default)
			)
			(layer "F.Fab")
		)
		(fp_line
			(start 0.120396 0.3048)
			(end 0.120396 0.2794)
			(stroke
				(width 0.1)
				(type default)
			)
			(layer "F.Fab")
		)
		(fp_line
			(start 0.67945 0.3048)
			(end 0.120396 0.3048)
			(stroke
				(width 0.1)
				(type default)
			)
			(layer "F.Fab")
		)
		(fp_line
			(start -0.12065 0.2794)
			(end -0.12065 0.3048)
			(stroke
				(width 0.1)
				(type default)
			)
			(layer "F.Fab")
		)
		(fp_line
			(start 0.120396 0.2794)
			(end -0.12065 0.2794)
			(stroke
				(width 0.1)
				(type default)
			)
			(layer "F.Fab")
		)
		(fp_line
			(start -0.12065 -0.2794)
			(end 0.12065 -0.2794)
			(stroke
				(width 0.1)
				(type default)
			)
			(layer "F.Fab")
		)
		(fp_line
			(start 0.12065 -0.2794)
			(end 0.12065 -0.3048)
			(stroke
				(width 0.1)
				(type default)
			)
			(layer "F.Fab")
		)
		(fp_line
			(start 0.12065 -0.3048)
			(end 0.67945 -0.3048)
			(stroke
				(width 0.1)
				(type default)
			)
			(layer "F.Fab")
		)
		(fp_line
			(start 0.67945 -0.3048)
			(end 0.67945 0.3048)
			(stroke
				(width 0.1)
				(type default)
			)
			(layer "F.Fab")
		)
		(fp_line
			(start -0.67945 -0.305054)
			(end -0.12065 -0.305054)
			(stroke
				(width 0.1)
				(type default)
			)
			(layer "F.Fab")
		)
		(fp_line
			(start -0.12065 -0.305054)
			(end -0.12065 -0.2794)
			(stroke
				(width 0.1)
				(type default)
			)
			(layer "F.Fab")
		)
		(pad "1" smd circle
			(at -0.40005 0 270)
			(size 0 0)
			(layers "F.Cu" "F.Mask" "F.Paste")
			(net "LED_PWRGD_PVCCFA_EHV_FIVRA_CPU1")
		)
		(pad "2" smd circle
			(at 0.40005 0 270)
			(size 0 0)
			(layers "F.Cu" "F.Mask" "F.Paste")
			(net "P3V3_AUX")
		)
	)
	(footprint ""
		(layer "F.Cu")
		(at 398.133824 -186.865514)
		(property "Reference" "PR521"
			(at 0 0 0)
			(layer "F.SilkS")
			(hide yes)
			(effects
				(font
					(size 1.27 1.27)
				)
			)
		)
		(property "Value" ""
			(at 0 0 0)
			(layer "F.Fab")
			(effects
				(font
					(size 1.27 1.27)
				)
			)
		)
		(duplicate_pad_numbers_are_jumpers no)
		(fp_line
			(start -0.7874 -0.4064)
			(end 0.7874 -0.4064)
			(stroke
				(width 0.1524)
				(type default)
			)
			(layer "F.SilkS")
		)
		(fp_line
			(start -0.7874 0.4064)
			(end -0.7874 -0.4064)
			(stroke
				(width 0.1524)
				(type default)
			)
			(layer "F.SilkS")
		)
		(fp_line
			(start 0.7874 -0.4064)
			(end 0.7874 0.4064)
			(stroke
				(width 0.1524)
				(type default)
			)
			(layer "F.SilkS")
		)
		(fp_line
			(start 0.7874 0.4064)
			(end -0.7874 0.4064)
			(stroke
				(width 0.1524)
				(type default)
			)
			(layer "F.SilkS")
		)
		(fp_line
			(start -0.67945 -0.305054)
			(end -0.12065 -0.305054)
			(stroke
				(width 0.1)
				(type default)
			)
			(layer "F.Fab")
		)
		(fp_line
			(start -0.67945 0.3048)
			(end -0.67945 -0.305054)
			(stroke
				(width 0.1)
				(type default)
			)
			(layer "F.Fab")
		)
		(fp_line
			(start -0.12065 -0.305054)
			(end -0.12065 -0.2794)
			(stroke
				(width 0.1)
				(type default)
			)
			(layer "F.Fab")
		)
		(fp_line
			(start -0.12065 -0.2794)
			(end 0.12065 -0.2794)
			(stroke
				(width 0.1)
				(type default)
			)
			(layer "F.Fab")
		)
		(fp_line
			(start -0.12065 0.2794)
			(end -0.12065 0.3048)
			(stroke
				(width 0.1)
				(type default)
			)
			(layer "F.Fab")
		)
		(fp_line
			(start -0.12065 0.3048)
			(end -0.67945 0.3048)
			(stroke
				(width 0.1)
				(type default)
			)
			(layer "F.Fab")
		)
		(fp_line
			(start 0.120396 0.2794)
			(end -0.12065 0.2794)
			(stroke
				(width 0.1)
				(type default)
			)
			(layer "F.Fab")
		)
		(fp_line
			(start 0.120396 0.3048)
			(end 0.120396 0.2794)
			(stroke
				(width 0.1)
				(type default)
			)
			(layer "F.Fab")
		)
		(fp_line
			(start 0.12065 -0.3048)
			(end 0.67945 -0.3048)
			(stroke
				(width 0.1)
				(type default)
			)
			(layer "F.Fab")
		)
		(fp_line
			(start 0.12065 -0.2794)
			(end 0.12065 -0.3048)
			(stroke
				(width 0.1)
				(type default)
			)
			(layer "F.Fab")
		)
		(fp_line
			(start 0.67945 -0.3048)
			(end 0.67945 0.3048)
			(stroke
				(width 0.1)
				(type default)
			)
			(layer "F.Fab")
		)
		(fp_line
			(start 0.67945 0.3048)
			(end 0.120396 0.3048)
			(stroke
				(width 0.1)
				(type default)
			)
			(layer "F.Fab")
		)
		(pad "1" smd circle
			(at -0.40005 0)
			(size 0 0)
			(layers "F.Cu" "F.Mask" "F.Paste")
			(net "VSENSE_PVCCINFAON_CPU0_DP")
		)
		(pad "2" smd circle
			(at 0.40005 0)
			(size 0 0)
			(layers "F.Cu" "F.Mask" "F.Paste")
			(net "PVCCINFAON_CPU0")
		)
	)
)
